# T6G (Grand Teton) — schematic netlist excerpt (pin names and nets, part order shuffled) for the footprints in the layout excerpt that follows; sources: Cadence DE-HDL packaged netlist, KiCad conversion of 04192023_DAF0TMB3IC0_F0TG_MB_C_brd_V02_OCP.brd

PR331  Q_RES  5.6 1% CHIP  pkg 0402LF  page 225 : A = SW_PVDD11_S3_P1_BOOT2 ; B = SW_PVDD11_S3_P1_BOOT2_RC
C223  Q_CAP  0.1UF 25V 10% X7R  pkg 0402  page 78 : A = P1V8_AUX ; B = GND

(kicad_pcb
	(version 20260206)
	(generator "pcbnew")
	(generator_version "10.0")
	(general
		(thickness 1.6)
		(legacy_teardrops no)
	)
	(paper "A4")
	(title_block
		(title "04192023_DAF0TMB3IC0_F0TG_MB_C_brd_V02_OCP.brd")
		(comment 1 "Grand Teton / footprints 2800-2801 of 8354")
	)
	(layers
		(0 "F.Cu" signal "TOP")
		(4 "In1.Cu" signal "GND")
		(6 "In2.Cu" signal "IN1")
		(8 "In3.Cu" signal "GND1")
		(10 "In4.Cu" signal "IN2")
		(12 "In5.Cu" signal "GND2")
		(14 "In6.Cu" signal "IN3")
		(16 "In7.Cu" signal "GND3")
		(18 "In8.Cu" signal "VCC")
		(20 "In9.Cu" signal "VCC1")
		(22 "In10.Cu" signal "GND4")
		(24 "In11.Cu" signal "IN4")
		(26 "In12.Cu" signal "GND5")
		(28 "In13.Cu" signal "IN5")
		(30 "In14.Cu" signal "GND6")
		(32 "In15.Cu" signal "IN6")
		(34 "In16.Cu" signal "GND7")
		(2 "B.Cu" signal "BOTTOM")
		(9 "F.Adhes" user "F.Adhesive")
		(11 "B.Adhes" user "B.Adhesive")
		(13 "F.Paste" user "Package Geometry/Pastemask Top")
		(15 "B.Paste" user "Package Geometry/Pastemask Bottom")
		(5 "F.SilkS" user "Ref Des/Silkscreen Top")
		(7 "B.SilkS" user "Ref Des/Silkscreen Bottom")
		(1 "F.Mask" user "Board Geometry/Soldermask Top")
		(3 "B.Mask" user "Board Geometry/Soldermask Bottom")
		(17 "Dwgs.User" user "User.Drawings")
		(19 "Cmts.User" user "User.Comments")
		(21 "Eco1.User" user "User.Eco1")
		(23 "Eco2.User" user "User.Eco2")
		(25 "Edge.Cuts" user "Board Geometry/Outline")
		(27 "Margin" user)
		(31 "F.CrtYd" user "Package Geometry/Place Bound Top")
		(29 "B.CrtYd" user "Package Geometry/Place Bound Bottom")
		(35 "F.Fab" user "Ref Des/Assembly Top")
		(33 "B.Fab" user "Ref Des/Assembly Bottom")
	)
	(footprint ""
		(layer "F.Cu")
		(at 391.845038 -143.151098 90)
		(property "Reference" "C223"
			(at 0 0 90)
			(layer "F.SilkS")
			(hide yes)
			(effects
				(font
					(size 1.27 1.27)
				)
			)
		)
		(property "Value" ""
			(at 0 0 90)
			(layer "F.Fab")
			(effects
				(font
					(size 1.27 1.27)
				)
			)
		)
		(duplicate_pad_numbers_are_jumpers no)
		(fp_line
			(start 0.7874 -0.4064)
			(end 0.7874 0.4064)
			(stroke
				(width 0.1524)
				(type default)
			)
			(layer "F.SilkS")
		)
		(fp_line
			(start -0.7874 -0.4064)
			(end 0.7874 -0.4064)
			(stroke
				(width 0.1524)
				(type default)
			)
			(layer "F.SilkS")
		)
		(fp_line
			(start 0.7874 0.4064)
			(end -0.7874 0.4064)
			(stroke
				(width 0.1524)
				(type default)
			)
			(layer "F.SilkS")
		)
		(fp_line
			(start -0.7874 0.4064)
			(end -0.7874 -0.4064)
			(stroke
				(width 0.1524)
				(type default)
			)
			(layer "F.SilkS")
		)
		(fp_line
			(start -0.12065 -0.305054)
			(end -0.12065 -0.2794)
			(stroke
				(width 0.1)
				(type default)
			)
			(layer "F.Fab")
		)
		(fp_line
			(start -0.67945 -0.305054)
			(end -0.12065 -0.305054)
			(stroke
				(width 0.1)
				(type default)
			)
			(layer "F.Fab")
		)
		(fp_line
			(start 0.67945 -0.3048)
			(end 0.67945 0.3048)
			(stroke
				(width 0.1)
				(type default)
			)
			(layer "F.Fab")
		)
		(fp_line
			(start 0.12065 -0.3048)
			(end 0.67945 -0.3048)
			(stroke
				(width 0.1)
				(type default)
			)
			(layer "F.Fab")
		)
		(fp_line
			(start 0.12065 -0.2794)
			(end 0.12065 -0.3048)
			(stroke
				(width 0.1)
				(type default)
			)
			(layer "F.Fab")
		)
		(fp_line
			(start -0.12065 -0.2794)
			(end 0.12065 -0.2794)
			(stroke
				(width 0.1)
				(type default)
			)
			(layer "F.Fab")
		)
		(fp_line
			(start 0.120396 0.2794)
			(end -0.12065 0.2794)
			(stroke
				(width 0.1)
				(type default)
			)
			(layer "F.Fab")
		)
		(fp_line
			(start -0.12065 0.2794)
			(end -0.12065 0.3048)
			(stroke
				(width 0.1)
				(type default)
			)
			(layer "F.Fab")
		)
		(fp_line
			(start 0.67945 0.3048)
			(end 0.120396 0.3048)
			(stroke
				(width 0.1)
				(type default)
			)
			(layer "F.Fab")
		)
		(fp_line
			(start 0.120396 0.3048)
			(end 0.120396 0.2794)
			(stroke
				(width 0.1)
				(type default)
			)
			(layer "F.Fab")
		)
		(fp_line
			(start -0.12065 0.3048)
			(end -0.67945 0.3048)
			(stroke
				(width 0.1)
				(type default)
			)
			(layer "F.Fab")
		)
		(fp_line
			(start -0.67945 0.3048)
			(end -0.67945 -0.305054)
			(stroke
				(width 0.1)
				(type default)
			)
			(layer "F.Fab")
		)
		(pad "1" smd circle
			(at -0.40005 0 90)
			(size 0 0)
			(layers "F.Cu" "F.Mask" "F.Paste")
			(net "P1V8_AUX")
		)
		(pad "2" smd circle
			(at 0.40005 0 90)
			(size 0 0)
			(layers "F.Cu" "F.Mask" "F.Paste")
			(net "GND")
		)
	)
	(footprint ""
		(layer "F.Cu")
		(at 192.005712 -355.924358 90)
		(property "Reference" "PR331"
			(at 0 0 90)
			(layer "F.SilkS")
			(hide yes)
			(effects
				(font
					(size 1.27 1.27)
				)
			)
		)
		(property "Value" ""
			(at 0 0 90)
			(layer "F.Fab")
			(effects
				(font
					(size 1.27 1.27)
				)
			)
		)
		(duplicate_pad_numbers_are_jumpers no)
		(fp_line
			(start 0.7874 -0.4064)
			(end 0.7874 0.4064)
			(stroke
				(width 0.1524)
				(type default)
			)
			(layer "F.SilkS")
		)
		(fp_line
			(start -0.7874 -0.4064)
			(end 0.7874 -0.4064)
			(stroke
				(width 0.1524)
				(type default)
			)
			(layer "F.SilkS")
		)
		(fp_line
			(start 0.7874 0.4064)
			(end -0.7874 0.4064)
			(stroke
				(width 0.1524)
				(type default)
			)
			(layer "F.SilkS")
		)
		(fp_line
			(start -0.7874 0.4064)
			(end -0.7874 -0.4064)
			(stroke
				(width 0.1524)
				(type default)
			)
			(layer "F.SilkS")
		)
		(fp_line
			(start -0.12065 -0.305054)
			(end -0.12065 -0.2794)
			(stroke
				(width 0.1)
				(type default)
			)
			(layer "F.Fab")
		)
		(fp_line
			(start -0.67945 -0.305054)
			(end -0.12065 -0.305054)
			(stroke
				(width 0.1)
				(type default)
			)
			(layer "F.Fab")
		)
		(fp_line
			(start 0.67945 -0.3048)
			(end 0.67945 0.3048)
			(stroke
				(width 0.1)
				(type default)
			)
			(layer "F.Fab")
		)
		(fp_line
			(start 0.12065 -0.3048)
			(end 0.67945 -0.3048)
			(stroke
				(width 0.1)
				(type default)
			)
			(layer "F.Fab")
		)
		(fp_line
			(start 0.12065 -0.2794)
			(end 0.12065 -0.3048)
			(stroke
				(width 0.1)
				(type default)
			)
			(layer "F.Fab")
		)
		(fp_line
			(start -0.12065 -0.2794)
			(end 0.12065 -0.2794)
			(stroke
				(width 0.1)
				(type default)
			)
			(layer "F.Fab")
		)
		(fp_line
			(start 0.120396 0.2794)
			(end -0.12065 0.2794)
			(stroke
				(width 0.1)
				(type default)
			)
			(layer "F.Fab")
		)
		(fp_line
			(start -0.12065 0.2794)
			(end -0.12065 0.3048)
			(stroke
				(width 0.1)
				(type default)
			)
			(layer "F.Fab")
		)
		(fp_line
			(start 0.67945 0.3048)
			(end 0.120396 0.3048)
			(stroke
				(width 0.1)
				(type default)
			)
			(layer "F.Fab")
		)
		(fp_line
			(start 0.120396 0.3048)
			(end 0.120396 0.2794)
			(stroke
				(width 0.1)
				(type default)
			)
			(layer "F.Fab")
		)
		(fp_line
			(start -0.12065 0.3048)
			(end -0.67945 0.3048)
			(stroke
				(width 0.1)
				(type default)
			)
			(layer "F.Fab")
		)
		(fp_line
			(start -0.67945 0.3048)
			(end -0.67945 -0.305054)
			(stroke
				(width 0.1)
				(type default)
			)
			(layer "F.Fab")
		)
		(pad "1" smd circle
			(at -0.40005 0 90)
			(size 0 0)
			(layers "F.Cu" "F.Mask" "F.Paste")
			(net "SW_PVDD11_S3_P1_BOOT2")
		)
		(pad "2" smd circle
			(at 0.40005 0 90)
			(size 0 0)
			(layers "F.Cu" "F.Mask" "F.Paste")
			(net "SW_PVDD11_S3_P1_BOOT2_RC")
		)
	)
)
